(kicad_pcb
	(version 20221018)
	(generator pcbnew)
	(general
    (thickness 1.518)
  )
	(paper "A4")
	(title_block
    (title "Kria K26 Devboard")
    (date "2024-03-26")
    (rev "1.2.5")
    (comment 1 "www.antmicro.com")
    (comment 2 "Antmicro Ltd.")
		(comment 9 "footprints 154-160 of 660")
	)
	(layers
    (0 "F.Cu" mixed)
    (1 "In1.Cu" power)
    (2 "In2.Cu" mixed)
    (3 "In3.Cu" power)
    (4 "In4.Cu" mixed)
    (5 "In5.Cu" power)
    (6 "In6.Cu" mixed)
    (31 "B.Cu" power)
    (32 "B.Adhes" user "B.Adhesive")
    (33 "F.Adhes" user "F.Adhesive")
    (34 "B.Paste" user)
    (35 "F.Paste" user)
    (36 "B.SilkS" user "B.Silkscreen")
    (37 "F.SilkS" user "F.Silkscreen")
    (38 "B.Mask" user)
    (39 "F.Mask" user)
    (40 "Dwgs.User" user "User.Drawings")
    (41 "Cmts.User" user "User.Comments")
    (42 "Eco1.User" user "User.Eco1")
    (43 "Eco2.User" user "User.Eco2")
    (44 "Edge.Cuts" user)
    (45 "Margin" user)
    (46 "B.CrtYd" user "B.Courtyard")
    (47 "F.CrtYd" user "F.Courtyard")
    (48 "B.Fab" user)
    (49 "F.Fab" user)
  )
	(footprint "kria-k26-devboard-footprints:TSOT23-6" (layer "F.Cu")
    (at 170.93 134.89)
    (property "Author" "Antmicro")
    (property "License" "Apache-2.0")
    (property "MPN" "AP62301WU-7")
    (property "Manufacturer" "Diodes Incorporated")
    (property "Sheetfile" "dc-dc-conventers.kicad_sch")
    (property "Sheetname" "DC/DC conventers")
    (property "ki_description" "DC-DC Switching Synchronous Buck Regulator, Adjustable, 4.2V-18Vin, 0.8V-7V/3A out, TSOT-26-6")
    (property "ki_keywords" "SMT, PMIC, IC, VOLTAGE")
    (attr smd)
    (fp_text reference "U49" (at 1.285 1.79) (layer "F.SilkS")
        (effects (font (size 0.7 0.7) (thickness 0.15)) (justify left bottom))
    )
    (fp_text value "AP62301_TSOT" (at -0.005 2.6) (layer "F.Fab") hide
        (effects (font (size 0.7 0.7) (thickness 0.15)) (justify left bottom))
    )
    (fp_text user "${REFERENCE}" (at -1.893 6.168) (layer "F.Fab") hide
        (effects (font (size 0.7 0.7) (thickness 0.15)) (justify left bottom))
    )
    (fp_text user "License: Apache-2.0" (at -1.893 4.967) (layer "F.Fab") hide
        (effects (font (size 0.7 0.7) (thickness 0.15)) (justify left bottom))
    )
    (fp_text user "Author: Antmicro" (at -1.893 7.368) (layer "F.Fab") hide
        (effects (font (size 0.7 0.7) (thickness 0.15)) (justify left bottom))
    )
    (fp_line (start -1.4805 0.725) (end -1.4795 -0.725)
      (stroke (width 0.15) (type solid)) (layer "F.SilkS"))
    (fp_line (start -1.4805 0.725) (end -1.3905 0.725)
      (stroke (width 0.15) (type solid)) (layer "F.SilkS"))
    (fp_line (start -1.4795 -0.725) (end -1.3905 -0.725)
      (stroke (width 0.15) (type solid)) (layer "F.SilkS"))
    (fp_line (start 1.479 0.73) (end 1.38 0.73)
      (stroke (width 0.15) (type solid)) (layer "F.SilkS"))
    (fp_line (start 1.48 -0.72) (end 1.38 -0.72)
      (stroke (width 0.15) (type solid)) (layer "F.SilkS"))
    (fp_line (start 1.48 -0.72) (end 1.479 0.73)
      (stroke (width 0.15) (type solid)) (layer "F.SilkS"))
    (fp_circle (center -1.499 1.236) (end -1.45 1.236)
      (stroke (width 0.15) (type solid)) (fill solid) (layer "F.SilkS"))
    (fp_rect (start -1.65 -1.61) (end 1.65 1.61)
      (stroke (width 0.05) (type solid)) (fill none) (layer "F.CrtYd"))
    (fp_line (start -1.527 -0.833) (end 1.523 -0.833)
      (stroke (width 0.15) (type solid)) (layer "F.Fab"))
    (fp_line (start -1.527 0.491) (end -1.527 -0.833)
      (stroke (width 0.15) (type solid)) (layer "F.Fab"))
    (fp_line (start -1.527 0.491) (end -1.102 0.916)
      (stroke (width 0.15) (type solid)) (layer "F.Fab"))
    (fp_line (start -1.102 0.916) (end 1.523 0.916)
      (stroke (width 0.15) (type solid)) (layer "F.Fab"))
    (fp_line (start 1.523 -0.833) (end 1.523 0.916)
      (stroke (width 0.15) (type solid)) (layer "F.Fab"))
    (pad "1" smd rect (at -0.952 1.18) (size 0.7 0.8) (layers "F.Cu" "F.Paste" "F.Mask")
      (net 1 "GND") (pinfunction "GND") (pintype "power_in"))
    (pad "2" smd rect (at -0.001 1.18) (size 0.7 0.8) (layers "F.Cu" "F.Paste" "F.Mask")
      (net 309 "/Power Supply/DC/DC conventers/SW_PS_3V3") (pinfunction "SW") (pintype "power_out"))
    (pad "3" smd rect (at 0.947 1.18) (size 0.7 0.8) (layers "F.Cu" "F.Paste" "F.Mask")
      (net 14 "/Power Supply/DC/DC conventers/DC_MAIN_BUS") (pinfunction "VIN") (pintype "power_in"))
    (pad "4" smd rect (at 0.947 -1.18) (size 0.7 0.8) (layers "F.Cu" "F.Paste" "F.Mask")
      (net 688 "Net-(U49-FB)") (pinfunction "FB") (pintype "input"))
    (pad "5" smd rect (at -0.001 -1.18) (size 0.7 0.8) (layers "F.Cu" "F.Paste" "F.Mask")
      (net 23 "/Power Supply/VCCOEN_PS_M2C") (pinfunction "EN") (pintype "input"))
    (pad "6" smd rect (at -0.952 -1.18) (size 0.7 0.8) (layers "F.Cu" "F.Paste" "F.Mask")
      (net 257 "Net-(U49-BST)") (pinfunction "BST") (pintype "output"))
  )
	(footprint "kria-k26-devboard-footprints:L_Coilcraft-XEL4030" (layer "F.Cu")
    (at 166.825 134.85 -90)
    (property "Author" "Antmicro")
    (property "IMax" "")
    (property "ISat" "")
    (property "License" "Apache-2.0")
    (property "MPN" "XEL4030-222MEC")
    (property "Manufacturer" "Coilcraft")
    (property "Sheetfile" "dc-dc-conventers.kicad_sch")
    (property "Sheetname" "DC/DC conventers")
    (property "Size" "4x4")
    (property "Val" "2u2/6.1A")
    (attr smd)
    (fp_text reference "L3" (at -1.86 3.505) (layer "F.SilkS")
        (effects (font (size 0.7 0.7) (thickness 0.15)) (justify left bottom))
    )
    (fp_text value "L_2u2_6.1A_XEL4030" (at 0.05 2.996 -90) (layer "F.Fab") hide
        (effects (font (size 0.7 0.7) (thickness 0.15)) (justify left bottom))
    )
    (fp_text user "Author: Antmicro" (at -2.15 5.996 -90) (layer "F.Fab") hide
        (effects (font (size 0.7 0.7) (thickness 0.15)) (justify left bottom))
    )
    (fp_text user "License: Apache-2.0" (at -2.15 6.996 -90) (layer "F.Fab") hide
        (effects (font (size 0.7 0.7) (thickness 0.15)) (justify left bottom))
    )
    (fp_text user "${REFERENCE}" (at -2.15 4.996 -90) (layer "F.Fab") hide
        (effects (font (size 0.7 0.7) (thickness 0.15)) (justify left bottom))
    )
    (fp_line (start -1.8 -2.2) (end 1.85 -2.201)
      (stroke (width 0.15) (type solid)) (layer "F.SilkS"))
    (fp_line (start -1.8 2.2) (end 1.85 2.199)
      (stroke (width 0.15) (type solid)) (layer "F.SilkS"))
    (fp_rect (start -2.45 -2.45) (end 2.45 2.45)
      (stroke (width 0.05) (type solid)) (fill none) (layer "F.CrtYd"))
    (fp_line (start -2 -2) (end 1.999 -2)
      (stroke (width 0.15) (type solid)) (layer "F.Fab"))
    (fp_line (start -2 1.999) (end -2 -2)
      (stroke (width 0.15) (type solid)) (layer "F.Fab"))
    (fp_line (start 1.999 -2) (end 1.999 1.999)
      (stroke (width 0.15) (type solid)) (layer "F.Fab"))
    (fp_line (start 1.999 1.999) (end -2 1.999)
      (stroke (width 0.15) (type solid)) (layer "F.Fab"))
    (pad "1" smd rect (at -1.186 0 270) (size 0.98 3.4) (layers "F.Cu" "F.Paste" "F.Mask")
      (net 309 "/Power Supply/DC/DC conventers/SW_PS_3V3") (pintype "passive"))
    (pad "2" smd rect (at 1.185 0 270) (size 0.98 3.4) (layers "F.Cu" "F.Paste" "F.Mask")
      (net 765 "/Power Supply/DC/DC conventers/PS_3V3_OUT") (pintype "passive"))
  )
	(footprint "kria-k26-devboard-footprints:LED_0603_1608Metric_G" (layer "F.Cu")
    (at 171.1 131.175)
    (descr "LED SMD 0603 Green")
    (tags "LED SMD 0603 Green")
    (property "Author" "Antmicro")
    (property "Color" "Green")
    (property "License" "Apache-2.0")
    (property "MPN" "LG L29K-G2J1-24-Z")
    (property "Manufacturer" "OSRAM")
    (property "Sheetfile" "dc-dc-conventers.kicad_sch")
    (property "Sheetname" "DC/DC conventers")
    (property "ki_description" "LED, Green, SMT, 0603, 20 mA, 2.1 V, 570 nm")
    (property "ki_keywords" "0603, SMT, DIODE, SEMICONDUCTOR, UNICOLOR")
    (attr smd)
    (fp_text reference "D14" (at -2.3 -0.605) (layer "F.SilkS")
        (effects (font (size 0.7 0.7) (thickness 0.15)) (justify left bottom))
    )
    (fp_text value "LED_G_0603_LG_L29K-G2J1-24-Z" (at 0 1.6) (layer "F.Fab") hide
        (effects (font (size 0.7 0.7) (thickness 0.15)) (justify left bottom))
    )
    (fp_text user "License: Apache-2.0" (at -1.31 5.769) (layer "F.Fab") hide
        (effects (font (size 0.7 0.7) (thickness 0.15)) (justify left bottom))
    )
    (fp_text user "${REFERENCE}" (at -1.31 3.769) (layer "F.Fab") hide
        (effects (font (size 0.7 0.7) (thickness 0.15)) (justify left bottom))
    )
    (fp_text user "Author: Antmicro" (at -1.31 4.769) (layer "F.Fab") hide
        (effects (font (size 0.7 0.7) (thickness 0.15)) (justify left bottom))
    )
    (fp_line (start -0.27 -0.35) (end 0.27 -0.35)
      (stroke (width 0.15) (type solid)) (layer "F.SilkS"))
    (fp_line (start -0.27 0.351) (end 0.27 0.351)
      (stroke (width 0.15) (type solid)) (layer "F.SilkS"))
    (fp_line (start -0.106328 -0.200008) (end -0.106328 0.199992)
      (stroke (width 0.1) (type solid)) (layer "F.SilkS"))
    (fp_line (start -0.106328 -0.200008) (end 0.093672 -0.000008)
      (stroke (width 0.1) (type solid)) (layer "F.SilkS"))
    (fp_line (start -0.106328 -0.000008) (end -0.29 0)
      (stroke (width 0.1) (type solid)) (layer "F.SilkS"))
    (fp_line (start 0.093672 -0.200008) (end 0.093672 0.199992)
      (stroke (width 0.1) (type solid)) (layer "F.SilkS"))
    (fp_line (start 0.093672 -0.000008) (end -0.106328 0.199992)
      (stroke (width 0.1) (type solid)) (layer "F.SilkS"))
    (fp_line (start 0.093672 -0.000008) (end 0.293672 -0.000008)
      (stroke (width 0.1) (type solid)) (layer "F.SilkS"))
    (fp_line (start 1.25 0.32) (end 1.25 -0.32)
      (stroke (width 0.15) (type solid)) (layer "F.SilkS"))
    (fp_rect (start 1.26 0.65) (end -1.26 -0.65)
      (stroke (width 0.05) (type solid)) (fill none) (layer "F.CrtYd"))
    (fp_line (start -0.599 0) (end -0.201 0)
      (stroke (width 0.15) (type solid)) (layer "F.Fab"))
    (fp_line (start -0.201 -0.2) (end -0.201 0)
      (stroke (width 0.15) (type solid)) (layer "F.Fab"))
    (fp_line (start -0.201 0) (end -0.201 0.202)
      (stroke (width 0.15) (type solid)) (layer "F.Fab"))
    (fp_line (start -0.201 0.202) (end 0.101 0)
      (stroke (width 0.15) (type solid)) (layer "F.Fab"))
    (fp_line (start 0.101 0) (end -0.201 -0.2)
      (stroke (width 0.15) (type solid)) (layer "F.Fab"))
    (fp_line (start 0.199 -0.2) (end 0.199 -0.1)
      (stroke (width 0.15) (type solid)) (layer "F.Fab"))
    (fp_line (start 0.199 0) (end 0.597 0)
      (stroke (width 0.15) (type solid)) (layer "F.Fab"))
    (fp_line (start 0.199 0.202) (end 0.199 -0.1)
      (stroke (width 0.15) (type solid)) (layer "F.Fab"))
    (fp_rect (start -0.848 -0.4) (end 0.85 0.402)
      (stroke (width 0.15) (type solid)) (fill none) (layer "F.Fab"))
    (pad "1" smd rect (at -0.75 0 180) (size 0.8 0.8) (layers "F.Cu" "F.Paste" "F.Mask")
      (net 239 "Net-(D14-Pad1)") (pintype "passive"))
    (pad "2" smd rect (at 0.75 0 180) (size 0.8 0.8) (layers "F.Cu" "F.Paste" "F.Mask")
      (net 1 "GND") (pinfunction "2") (pintype "passive"))
  )
	(footprint "kria-k26-devboard-footprints:C_0402_1005Metric" (layer "F.Cu")
    (at 86.6 71.317 90)
    (descr "Capacitor SMD 0402")
    (tags "capacitor SMD 0402")
    (property "Author" "Antmicro")
    (property "Dielectric" "X5R")
    (property "License" "Apache-2.0")
    (property "MPN" "GRM155R61H104KE14D")
    (property "Manufacturer" "Murata")
    (property "Sheetfile" "dp.kicad_sch")
    (property "Sheetname" "Display Port")
    (property "Val" "100n")
    (property "Voltage" "50V")
    (property "ki_description" " ")
    (attr smd)
    (fp_text reference "C8" (at -2.403 0.37 90) (layer "F.SilkS")
        (effects (font (size 0.7 0.7) (thickness 0.15)) (justify left bottom))
    )
    (fp_text value "C_100n_0402" (at 0 1.4 90) (layer "F.Fab") hide
        (effects (font (size 0.7 0.7) (thickness 0.15)) (justify left bottom))
    )
    (fp_text user "${REFERENCE}" (at -0.932 3.168 90) (layer "F.Fab") hide
        (effects (font (size 0.7 0.7) (thickness 0.15)) (justify left bottom))
    )
    (fp_text user "Author: Antmicro" (at -0.932 4.17 90) (layer "F.Fab") hide
        (effects (font (size 0.7 0.7) (thickness 0.15)) (justify left bottom))
    )
    (fp_text user "License: Apache-2.0" (at -0.932 5.17 90) (layer "F.Fab") hide
        (effects (font (size 0.7 0.7) (thickness 0.15)) (justify left bottom))
    )
    (fp_rect (start -0.94 -0.47) (end 0.94 0.47)
      (stroke (width 0.05) (type solid)) (fill none) (layer "F.CrtYd"))
    (fp_rect (start -0.499 -0.249) (end 0.499 0.249)
      (stroke (width 0.15) (type solid)) (fill none) (layer "F.Fab"))
    (pad "1" smd roundrect (at -0.484 0 90) (size 0.59 0.64) (layers "F.Cu" "F.Paste" "F.Mask") (roundrect_rratio 0.25)
      (net 100 "/Display Port/GTR_DP0_M2C_P") (pintype "passive"))
    (pad "2" smd roundrect (at 0.484 0 90) (size 0.59 0.64) (layers "F.Cu" "F.Paste" "F.Mask") (roundrect_rratio 0.25)
      (net 101 "/Display Port/GTR_DP0_M2C_C_P") (pintype "passive"))
  )
	(footprint "kria-k26-devboard-footprints:C_0402_1005Metric" (layer "F.Cu")
    (at 87.59 71.317 90)
    (descr "Capacitor SMD 0402")
    (tags "capacitor SMD 0402")
    (property "Author" "Antmicro")
    (property "Dielectric" "X5R")
    (property "License" "Apache-2.0")
    (property "MPN" "GRM155R61H104KE14D")
    (property "Manufacturer" "Murata")
    (property "Sheetfile" "dp.kicad_sch")
    (property "Sheetname" "Display Port")
    (property "Val" "100n")
    (property "Voltage" "50V")
    (property "ki_description" " ")
    (attr smd)
    (fp_text reference "C9" (at -2.403 0.37 90) (layer "F.SilkS")
        (effects (font (size 0.7 0.7) (thickness 0.15)) (justify left bottom))
    )
    (fp_text value "C_100n_0402" (at 0 1.4 90) (layer "F.Fab") hide
        (effects (font (size 0.7 0.7) (thickness 0.15)) (justify left bottom))
    )
    (fp_text user "Author: Antmicro" (at -0.932 4.17 90) (layer "F.Fab") hide
        (effects (font (size 0.7 0.7) (thickness 0.15)) (justify left bottom))
    )
    (fp_text user "${REFERENCE}" (at -0.932 3.168 90) (layer "F.Fab") hide
        (effects (font (size 0.7 0.7) (thickness 0.15)) (justify left bottom))
    )
    (fp_text user "License: Apache-2.0" (at -0.932 5.17 90) (layer "F.Fab") hide
        (effects (font (size 0.7 0.7) (thickness 0.15)) (justify left bottom))
    )
    (fp_rect (start -0.94 -0.47) (end 0.94 0.47)
      (stroke (width 0.05) (type solid)) (fill none) (layer "F.CrtYd"))
    (fp_rect (start -0.499 -0.249) (end 0.499 0.249)
      (stroke (width 0.15) (type solid)) (fill none) (layer "F.Fab"))
    (pad "1" smd roundrect (at -0.484 0 90) (size 0.59 0.64) (layers "F.Cu" "F.Paste" "F.Mask") (roundrect_rratio 0.25)
      (net 102 "/Display Port/GTR_DP0_M2C_N") (pintype "passive"))
    (pad "2" smd roundrect (at 0.484 0 90) (size 0.59 0.64) (layers "F.Cu" "F.Paste" "F.Mask") (roundrect_rratio 0.25)
      (net 103 "/Display Port/GTR_DP0_M2C_C_N") (pintype "passive"))
  )
	(footprint "kria-k26-devboard-footprints:Oscillator_SMD_Geyer_KX-7-4Pin_3.2x2.5mm" (layer "F.Cu")
    (at 150.21906 125.686827)
    (property "Author" "Antmicro")
    (property "License" "Apache-2.0")
    (property "MPN" "ABM8G-12.000MHZ-18-D2Y-T")
    (property "Manufacturer" "Abracon")
    (property "Sheetfile" "debug.kicad_sch")
    (property "Sheetname" "Debug and JTAG")
    (property "Val" "12 MHz")
    (property "ki_description" "Crystal, 12 MHz, SMT, 3.2mm x 2.5mm, 30 ppm, 18 pF, 20 ppm, ABM8G")
    (property "ki_keywords" "SMT, CERAMIC, OSCILLATOR")
    (attr smd)
    (fp_text reference "Y7" (at -1.46906 2.383173 180) (layer "F.SilkS")
        (effects (font (size 0.7 0.7) (thickness 0.15)) (justify left bottom))
    )
    (fp_text value "Resonator_12MHz_ABM8G" (at -1.75 2.548) (layer "F.Fab") hide
        (effects (font (size 0.7 0.7) (thickness 0.15)) (justify left bottom))
    )
    (fp_text user "License: Apache-2.0" (at -1.75 6.5) (layer "F.Fab") hide
        (effects (font (size 0.7 0.7) (thickness 0.15)) (justify left bottom))
    )
    (fp_text user "${REFERENCE}" (at -1.75 3.75) (layer "F.Fab") hide
        (effects (font (size 0.7 0.7) (thickness 0.15)) (justify left bottom))
    )
    (fp_text user "Author: Antmicro" (at -1.75 5) (layer "F.Fab") hide
        (effects (font (size 0.7 0.7) (thickness 0.15)) (justify left bottom))
    )
    (fp_line (start -1.6 0.3) (end -1.6 -0.2)
      (stroke (width 0.15) (type solid)) (layer "F.SilkS"))
    (fp_line (start -0.35 -1.25) (end 0.45 -1.25)
      (stroke (width 0.15) (type solid)) (layer "F.SilkS"))
    (fp_line (start -0.35 1.25) (end 0.45 1.25)
      (stroke (width 0.15) (type solid)) (layer "F.SilkS"))
    (fp_line (start 1.6 0.3) (end 1.6 -0.2)
      (stroke (width 0.15) (type solid)) (layer "F.SilkS"))
    (fp_circle (center -1.75 1.5) (end -1.7 1.5)
      (stroke (width 0.15) (type solid)) (fill none) (layer "F.SilkS"))
    (fp_rect (start -1.907 -1.55) (end 2.006 1.649)
      (stroke (width 0.05) (type solid)) (fill none) (layer "F.CrtYd"))
    (pad "1" smd roundrect (at -1.101 0.949) (size 1.3 1.1) (layers "F.Cu" "F.Paste" "F.Mask") (roundrect_rratio 0)
      (chamfer_ratio 0.2) (chamfer bottom_left)
      (net 137 "/Debug and JTAG/XIN") (pintype "passive"))
    (pad "2" smd rect (at 1.199 0.949) (size 1.3 1.1) (layers "F.Cu" "F.Paste" "F.Mask")
      (net 1 "GND") (pinfunction "SH") (pintype "passive"))
    (pad "3" smd rect (at 1.199 -0.85) (size 1.3 1.1) (layers "F.Cu" "F.Paste" "F.Mask")
      (net 139 "/Debug and JTAG/XOUT") (pintype "passive"))
    (pad "4" smd rect (at -1.101 -0.85) (size 1.3 1.1) (layers "F.Cu" "F.Paste" "F.Mask")
      (net 1 "GND") (pinfunction "SH") (pintype "passive"))
  )
	(footprint "kria-k26-devboard-footprints:C_0402_1005Metric" (layer "F.Cu")
    (at 127.3 95.025)
    (descr "Capacitor SMD 0402")
    (tags "capacitor SMD 0402")
    (property "Author" "Antmicro")
    (property "Dielectric" "X5R")
    (property "License" "Apache-2.0")
    (property "MPN" "GRM155R61H104KE14D")
    (property "Manufacturer" "Murata")
    (property "Sheetfile" "usb.kicad_sch")
    (property "Sheetname" "USB")
    (property "Val" "100n")
    (property "Voltage" "50V")
    (property "ki_description" " ")
    (attr smd)
    (fp_text reference "C39" (at 0.76 0.375) (layer "F.SilkS")
        (effects (font (size 0.7 0.7) (thickness 0.15)) (justify left bottom))
    )
    (fp_text value "C_100n_0402" (at 0 1.4) (layer "F.Fab") hide
        (effects (font (size 0.7 0.7) (thickness 0.15)) (justify left bottom))
    )
    (fp_text user "Author: Antmicro" (at -0.932 4.17) (layer "F.Fab") hide
        (effects (font (size 0.7 0.7) (thickness 0.15)) (justify left bottom))
    )
    (fp_text user "${REFERENCE}" (at -0.932 3.168) (layer "F.Fab") hide
        (effects (font (size 0.7 0.7) (thickness 0.15)) (justify left bottom))
    )
    (fp_text user "License: Apache-2.0" (at -0.932 5.17) (layer "F.Fab") hide
        (effects (font (size 0.7 0.7) (thickness 0.15)) (justify left bottom))
    )
    (fp_rect (start -0.94 -0.47) (end 0.94 0.47)
      (stroke (width 0.05) (type solid)) (fill none) (layer "F.CrtYd"))
    (fp_rect (start -0.499 -0.249) (end 0.499 0.249)
      (stroke (width 0.15) (type solid)) (fill none) (layer "F.Fab"))
    (pad "1" smd roundrect (at -0.484 0) (size 0.59 0.64) (layers "F.Cu" "F.Paste" "F.Mask") (roundrect_rratio 0.25)
      (net 15 "PS_3V3") (pintype "passive"))
    (pad "2" smd roundrect (at 0.484 0) (size 0.59 0.64) (layers "F.Cu" "F.Paste" "F.Mask") (roundrect_rratio 0.25)
      (net 1 "GND") (pintype "passive"))
  )
)
